(kicad_pcb
	(version 20260206)
	(generator "pcbnew")
	(generator_version "10.0")
	(general
		(thickness 1.6)
		(legacy_teardrops no)
	)
	(paper "A4")
	(title_block
		(title "03242023_DA0F0TMBIJ0_F0T_Motherboard_J_brd_V01_OCP.brd")
		(comment 1 "Grand Teton / footprints 4721-4728 of 6105")
	)
	(layers
		(0 "F.Cu" signal "TOP")
		(4 "In1.Cu" signal "GND")
		(6 "In2.Cu" signal "IN1")
		(8 "In3.Cu" signal "GND1")
		(10 "In4.Cu" signal "IN2")
		(12 "In5.Cu" signal "GND2")
		(14 "In6.Cu" signal "IN3")
		(16 "In7.Cu" signal "GND3")
		(18 "In8.Cu" signal "VCC")
		(20 "In9.Cu" signal "VCC1")
		(22 "In10.Cu" signal "GND4")
		(24 "In11.Cu" signal "IN4")
		(26 "In12.Cu" signal "GND5")
		(28 "In13.Cu" signal "IN5")
		(30 "In14.Cu" signal "GND6")
		(32 "In15.Cu" signal "IN6")
		(34 "In16.Cu" signal "GND7")
		(2 "B.Cu" signal "BOTTOM")
		(9 "F.Adhes" user "F.Adhesive")
		(11 "B.Adhes" user "B.Adhesive")
		(13 "F.Paste" user "Package Geometry/Pastemask Top")
		(15 "B.Paste" user "Package Geometry/Pastemask Bottom")
		(5 "F.SilkS" user "Ref Des/Silkscreen Top")
		(7 "B.SilkS" user "Ref Des/Silkscreen Bottom")
		(1 "F.Mask" user "Board Geometry/Soldermask Top")
		(3 "B.Mask" user "Board Geometry/Soldermask Bottom")
		(17 "Dwgs.User" user "User.Drawings")
		(19 "Cmts.User" user "User.Comments")
		(21 "Eco1.User" user "User.Eco1")
		(23 "Eco2.User" user "User.Eco2")
		(25 "Edge.Cuts" user "Board Geometry/Outline")
		(27 "Margin" user)
		(31 "F.CrtYd" user "Package Geometry/Place Bound Top")
		(29 "B.CrtYd" user "Package Geometry/Place Bound Bottom")
		(35 "F.Fab" user "Ref Des/Assembly Top")
		(33 "B.Fab" user "Ref Des/Assembly Bottom")
	)
	(footprint ""
		(layer "B.Cu")
		(at 108.845604 -296.05478 180)
		(property "Reference" "C346"
			(at 0 0 0)
			(layer "B.SilkS")
			(hide yes)
			(effects
				(font
					(size 1.27 1.27)
				)
				(justify mirror)
			)
		)
		(property "Value" ""
			(at 0 0 0)
			(layer "B.Fab")
			(effects
				(font
					(size 1.27 1.27)
				)
				(justify mirror)
			)
		)
		(duplicate_pad_numbers_are_jumpers no)
		(fp_line
			(start 1.524 0.762)
			(end 1.524 -0.762)
			(stroke
				(width 0.1524)
				(type default)
			)
			(layer "B.SilkS")
		)
		(fp_line
			(start 1.524 -0.762)
			(end -1.524 -0.762)
			(stroke
				(width 0.1524)
				(type default)
			)
			(layer "B.SilkS")
		)
		(fp_line
			(start -1.524 0.762)
			(end 1.524 0.762)
			(stroke
				(width 0.1524)
				(type default)
			)
			(layer "B.SilkS")
		)
		(fp_line
			(start -1.524 -0.762)
			(end -1.524 0.762)
			(stroke
				(width 0.1524)
				(type default)
			)
			(layer "B.SilkS")
		)
		(fp_line
			(start 1.1049 0.724916)
			(end -1.1049 0.724916)
			(stroke
				(width 0.1)
				(type default)
			)
			(layer "B.Fab")
		)
		(fp_line
			(start 1.1049 -0.724916)
			(end 1.1049 0.724916)
			(stroke
				(width 0.1)
				(type default)
			)
			(layer "B.Fab")
		)
		(fp_line
			(start -1.1049 0.724916)
			(end -1.1049 -0.724916)
			(stroke
				(width 0.1)
				(type default)
			)
			(layer "B.Fab")
		)
		(fp_line
			(start -1.1049 -0.724916)
			(end 1.1049 -0.724916)
			(stroke
				(width 0.1)
				(type default)
			)
			(layer "B.Fab")
		)
		(pad "1" smd rect
			(at 0.889 0 180)
			(size 1.016 1.27)
			(layers "B.Cu" "B.Mask" "B.Paste")
			(net "PVCCIN_CPU1")
		)
		(pad "2" smd rect
			(at -0.889 0 180)
			(size 1.016 1.27)
			(layers "B.Cu" "B.Mask" "B.Paste")
			(net "GND")
		)
	)
	(footprint ""
		(layer "B.Cu")
		(at 216.18448 -54.955948)
		(property "Reference" "C2069"
			(at 0 0 0)
			(layer "B.SilkS")
			(hide yes)
			(effects
				(font
					(size 1.27 1.27)
				)
				(justify mirror)
			)
		)
		(property "Value" ""
			(at 0 0 0)
			(layer "B.Fab")
			(effects
				(font
					(size 1.27 1.27)
				)
				(justify mirror)
			)
		)
		(duplicate_pad_numbers_are_jumpers no)
		(fp_line
			(start -0.7874 -0.4064)
			(end -0.7874 0.4064)
			(stroke
				(width 0.1524)
				(type default)
			)
			(layer "B.SilkS")
		)
		(fp_line
			(start -0.7874 0.4064)
			(end 0.7874 0.4064)
			(stroke
				(width 0.1524)
				(type default)
			)
			(layer "B.SilkS")
		)
		(fp_line
			(start 0.7874 -0.4064)
			(end -0.7874 -0.4064)
			(stroke
				(width 0.1524)
				(type default)
			)
			(layer "B.SilkS")
		)
		(fp_line
			(start 0.7874 0.4064)
			(end 0.7874 -0.4064)
			(stroke
				(width 0.1524)
				(type default)
			)
			(layer "B.SilkS")
		)
		(fp_line
			(start -0.67945 -0.3048)
			(end -0.67945 0.3048)
			(stroke
				(width 0.1)
				(type default)
			)
			(layer "B.Fab")
		)
		(fp_line
			(start -0.67945 0.3048)
			(end -0.120396 0.3048)
			(stroke
				(width 0.1)
				(type default)
			)
			(layer "B.Fab")
		)
		(fp_line
			(start -0.12065 -0.3048)
			(end -0.67945 -0.3048)
			(stroke
				(width 0.1)
				(type default)
			)
			(layer "B.Fab")
		)
		(fp_line
			(start -0.12065 -0.2794)
			(end -0.12065 -0.3048)
			(stroke
				(width 0.1)
				(type default)
			)
			(layer "B.Fab")
		)
		(fp_line
			(start -0.120396 0.2794)
			(end 0.12065 0.2794)
			(stroke
				(width 0.1)
				(type default)
			)
			(layer "B.Fab")
		)
		(fp_line
			(start -0.120396 0.3048)
			(end -0.120396 0.2794)
			(stroke
				(width 0.1)
				(type default)
			)
			(layer "B.Fab")
		)
		(fp_line
			(start 0.12065 -0.305054)
			(end 0.12065 -0.2794)
			(stroke
				(width 0.1)
				(type default)
			)
			(layer "B.Fab")
		)
		(fp_line
			(start 0.12065 -0.2794)
			(end -0.12065 -0.2794)
			(stroke
				(width 0.1)
				(type default)
			)
			(layer "B.Fab")
		)
		(fp_line
			(start 0.12065 0.2794)
			(end 0.12065 0.3048)
			(stroke
				(width 0.1)
				(type default)
			)
			(layer "B.Fab")
		)
		(fp_line
			(start 0.12065 0.3048)
			(end 0.67945 0.3048)
			(stroke
				(width 0.1)
				(type default)
			)
			(layer "B.Fab")
		)
		(fp_line
			(start 0.67945 -0.305054)
			(end 0.12065 -0.305054)
			(stroke
				(width 0.1)
				(type default)
			)
			(layer "B.Fab")
		)
		(fp_line
			(start 0.67945 0.3048)
			(end 0.67945 -0.305054)
			(stroke
				(width 0.1)
				(type default)
			)
			(layer "B.Fab")
		)
		(pad "1" smd circle
			(at 0.40005 0 180)
			(size 0 0)
			(layers "B.Cu" "B.Mask" "B.Paste")
			(net "P3V3_E1S_0_R")
		)
		(pad "2" smd circle
			(at -0.40005 0 180)
			(size 0 0)
			(layers "B.Cu" "B.Mask" "B.Paste")
			(net "GND")
		)
	)
	(footprint ""
		(layer "B.Cu")
		(at 324.332854 -66.83375 -90)
		(property "Reference" "C1201"
			(at 0 0 90)
			(layer "B.SilkS")
			(hide yes)
			(effects
				(font
					(size 1.27 1.27)
				)
				(justify mirror)
			)
		)
		(property "Value" ""
			(at 0 0 90)
			(layer "B.Fab")
			(effects
				(font
					(size 1.27 1.27)
				)
				(justify mirror)
			)
		)
		(duplicate_pad_numbers_are_jumpers no)
		(fp_line
			(start -1.2954 0.5842)
			(end 1.2954 0.5842)
			(stroke
				(width 0.1524)
				(type default)
			)
			(layer "B.SilkS")
		)
		(fp_line
			(start 1.2954 0.5842)
			(end 1.2954 -0.5842)
			(stroke
				(width 0.1524)
				(type default)
			)
			(layer "B.SilkS")
		)
		(fp_line
			(start -1.2954 -0.5842)
			(end -1.2954 0.5842)
			(stroke
				(width 0.1524)
				(type default)
			)
			(layer "B.SilkS")
		)
		(fp_line
			(start 0 -0.5842)
			(end 0 0.5842)
			(stroke
				(width 0.1524)
				(type default)
			)
			(layer "B.SilkS")
		)
		(fp_line
			(start 1.2954 -0.5842)
			(end -1.2954 -0.5842)
			(stroke
				(width 0.1524)
				(type default)
			)
			(layer "B.SilkS")
		)
		(fp_line
			(start -0.8636 0.4572)
			(end 0.8636 0.4572)
			(stroke
				(width 0.1)
				(type default)
			)
			(layer "B.Fab")
		)
		(fp_line
			(start 0.8636 0.4572)
			(end 0.8636 0.4064)
			(stroke
				(width 0.1)
				(type default)
			)
			(layer "B.Fab")
		)
		(fp_line
			(start -1.1938 0.4064)
			(end -0.8636 0.4064)
			(stroke
				(width 0.1)
				(type default)
			)
			(layer "B.Fab")
		)
		(fp_line
			(start -0.8636 0.4064)
			(end -0.8636 0.4572)
			(stroke
				(width 0.1)
				(type default)
			)
			(layer "B.Fab")
		)
		(fp_line
			(start 0.8636 0.4064)
			(end 1.1938 0.4064)
			(stroke
				(width 0.1)
				(type default)
			)
			(layer "B.Fab")
		)
		(fp_line
			(start 1.1938 0.4064)
			(end 1.1938 -0.4064)
			(stroke
				(width 0.1)
				(type default)
			)
			(layer "B.Fab")
		)
		(fp_line
			(start -1.1938 -0.4064)
			(end -1.1938 0.4064)
			(stroke
				(width 0.1)
				(type default)
			)
			(layer "B.Fab")
		)
		(fp_line
			(start -0.8636 -0.4064)
			(end -1.1938 -0.4064)
			(stroke
				(width 0.1)
				(type default)
			)
			(layer "B.Fab")
		)
		(fp_line
			(start 0.8636 -0.4064)
			(end 0.8636 -0.4572)
			(stroke
				(width 0.1)
				(type default)
			)
			(layer "B.Fab")
		)
		(fp_line
			(start 1.1938 -0.4064)
			(end 0.8636 -0.4064)
			(stroke
				(width 0.1)
				(type default)
			)
			(layer "B.Fab")
		)
		(fp_line
			(start -0.8636 -0.4572)
			(end -0.8636 -0.4064)
			(stroke
				(width 0.1)
				(type default)
			)
			(layer "B.Fab")
		)
		(fp_line
			(start 0.8636 -0.4572)
			(end -0.8636 -0.4572)
			(stroke
				(width 0.1)
				(type default)
			)
			(layer "B.Fab")
		)
		(pad "1" smd rect
			(at 0.7366 0 180)
			(size 0.7112 0.8128)
			(layers "B.Cu" "B.Mask" "B.Paste")
			(net "P3V3_AUX")
		)
		(pad "2" smd rect
			(at -0.7366 0 180)
			(size 0.7112 0.8128)
			(layers "B.Cu" "B.Mask" "B.Paste")
			(net "GND")
		)
	)
	(footprint ""
		(layer "B.Cu")
		(at 348.2467 -359.788714 180)
		(property "Reference" "R2379"
			(at 0 0 0)
			(layer "B.SilkS")
			(hide yes)
			(effects
				(font
					(size 1.27 1.27)
				)
				(justify mirror)
			)
		)
		(property "Value" ""
			(at 0 0 0)
			(layer "B.Fab")
			(effects
				(font
					(size 1.27 1.27)
				)
				(justify mirror)
			)
		)
		(duplicate_pad_numbers_are_jumpers no)
		(fp_line
			(start 0.7874 0.4064)
			(end 0.7874 -0.4064)
			(stroke
				(width 0.1524)
				(type default)
			)
			(layer "B.SilkS")
		)
		(fp_line
			(start 0.7874 -0.4064)
			(end -0.7874 -0.4064)
			(stroke
				(width 0.1524)
				(type default)
			)
			(layer "B.SilkS")
		)
		(fp_line
			(start -0.7874 0.4064)
			(end 0.7874 0.4064)
			(stroke
				(width 0.1524)
				(type default)
			)
			(layer "B.SilkS")
		)
		(fp_line
			(start -0.7874 -0.4064)
			(end -0.7874 0.4064)
			(stroke
				(width 0.1524)
				(type default)
			)
			(layer "B.SilkS")
		)
		(fp_line
			(start 0.67945 0.3048)
			(end 0.67945 -0.305054)
			(stroke
				(width 0.1)
				(type default)
			)
			(layer "B.Fab")
		)
		(fp_line
			(start 0.67945 -0.305054)
			(end 0.12065 -0.305054)
			(stroke
				(width 0.1)
				(type default)
			)
			(layer "B.Fab")
		)
		(fp_line
			(start 0.12065 0.3048)
			(end 0.67945 0.3048)
			(stroke
				(width 0.1)
				(type default)
			)
			(layer "B.Fab")
		)
		(fp_line
			(start 0.12065 0.2794)
			(end 0.12065 0.3048)
			(stroke
				(width 0.1)
				(type default)
			)
			(layer "B.Fab")
		)
		(fp_line
			(start 0.12065 -0.2794)
			(end -0.12065 -0.2794)
			(stroke
				(width 0.1)
				(type default)
			)
			(layer "B.Fab")
		)
		(fp_line
			(start 0.12065 -0.305054)
			(end 0.12065 -0.2794)
			(stroke
				(width 0.1)
				(type default)
			)
			(layer "B.Fab")
		)
		(fp_line
			(start -0.120396 0.3048)
			(end -0.120396 0.2794)
			(stroke
				(width 0.1)
				(type default)
			)
			(layer "B.Fab")
		)
		(fp_line
			(start -0.120396 0.2794)
			(end 0.12065 0.2794)
			(stroke
				(width 0.1)
				(type default)
			)
			(layer "B.Fab")
		)
		(fp_line
			(start -0.12065 -0.2794)
			(end -0.12065 -0.3048)
			(stroke
				(width 0.1)
				(type default)
			)
			(layer "B.Fab")
		)
		(fp_line
			(start -0.12065 -0.3048)
			(end -0.67945 -0.3048)
			(stroke
				(width 0.1)
				(type default)
			)
			(layer "B.Fab")
		)
		(fp_line
			(start -0.67945 0.3048)
			(end -0.120396 0.3048)
			(stroke
				(width 0.1)
				(type default)
			)
			(layer "B.Fab")
		)
		(fp_line
			(start -0.67945 -0.3048)
			(end -0.67945 0.3048)
			(stroke
				(width 0.1)
				(type default)
			)
			(layer "B.Fab")
		)
		(pad "1" smd circle
			(at 0.40005 0)
			(size 0 0)
			(layers "B.Cu" "B.Mask" "B.Paste")
			(net "PWRGD_PVCCFA_EHV_FIVRA_CPU0")
		)
		(pad "2" smd circle
			(at -0.40005 0)
			(size 0 0)
			(layers "B.Cu" "B.Mask" "B.Paste")
			(net "PWRGD_PVCCFA_EHV_FIVRA_CPU0_R")
		)
	)
	(footprint ""
		(layer "B.Cu")
		(at 456.24496 -32.250888)
		(property "Reference" ""
			(at 0 0 0)
			(layer "B.SilkS")
			(hide yes)
			(effects
				(font
					(size 1.27 1.27)
				)
				(justify mirror)
			)
		)
		(property "Value" ""
			(at 0 0 0)
			(layer "B.Fab")
			(effects
				(font
					(size 1.27 1.27)
				)
				(justify mirror)
			)
		)
		(duplicate_pad_numbers_are_jumpers no)
		(pad "1" smd circle
			(at 0 0 180)
			(size 0.9906 0.9906)
			(layers "B.Cu" "B.Mask" "B.Paste")
			(net "Net_292")
		)
		(zone
			(layer "B.Cu")
			(hatch none 0.5)
			(connect_pads
				(clearance 0)
			)
			(min_thickness 0.25)
			(keepout
				(tracks not_allowed)
				(vias allowed)
				(pads allowed)
				(copperpour not_allowed)
				(footprints allowed)
			)
			(placement
				(enabled no)
				(sheetname "")
			)
			(fill
				(thermal_gap 0.5)
				(thermal_bridge_width 0.5)
				(island_removal_mode 0)
			)
			(polygon
				(pts
					(arc
						(start 457.87056 -32.250888)
						(mid 454.61936 -32.250888)
						(end 457.87056 -32.250888)
					)
				)
			)
		)
	)
	(footprint ""
		(layer "B.Cu")
		(at 107.457494 -241.21872 90)
		(property "Reference" "C315"
			(at 0 0 90)
			(layer "B.SilkS")
			(hide yes)
			(effects
				(font
					(size 1.27 1.27)
				)
				(justify mirror)
			)
		)
		(property "Value" ""
			(at 0 0 90)
			(layer "B.Fab")
			(effects
				(font
					(size 1.27 1.27)
				)
				(justify mirror)
			)
		)
		(duplicate_pad_numbers_are_jumpers no)
		(fp_line
			(start 1.524 -0.762)
			(end -1.524 -0.762)
			(stroke
				(width 0.1524)
				(type default)
			)
			(layer "B.SilkS")
		)
		(fp_line
			(start -1.524 -0.762)
			(end -1.524 0.762)
			(stroke
				(width 0.1524)
				(type default)
			)
			(layer "B.SilkS")
		)
		(fp_line
			(start 1.524 0.762)
			(end 1.524 -0.762)
			(stroke
				(width 0.1524)
				(type default)
			)
			(layer "B.SilkS")
		)
		(fp_line
			(start -1.524 0.762)
			(end 1.524 0.762)
			(stroke
				(width 0.1524)
				(type default)
			)
			(layer "B.SilkS")
		)
		(fp_line
			(start 1.1049 -0.724916)
			(end 1.1049 0.724916)
			(stroke
				(width 0.1)
				(type default)
			)
			(layer "B.Fab")
		)
		(fp_line
			(start -1.1049 -0.724916)
			(end 1.1049 -0.724916)
			(stroke
				(width 0.1)
				(type default)
			)
			(layer "B.Fab")
		)
		(fp_line
			(start 1.1049 0.724916)
			(end -1.1049 0.724916)
			(stroke
				(width 0.1)
				(type default)
			)
			(layer "B.Fab")
		)
		(fp_line
			(start -1.1049 0.724916)
			(end -1.1049 -0.724916)
			(stroke
				(width 0.1)
				(type default)
			)
			(layer "B.Fab")
		)
		(pad "1" smd rect
			(at 0.889 0 90)
			(size 1.016 1.27)
			(layers "B.Cu" "B.Mask" "B.Paste")
			(net "PVCCIN_CPU1")
		)
		(pad "2" smd rect
			(at -0.889 0 90)
			(size 1.016 1.27)
			(layers "B.Cu" "B.Mask" "B.Paste")
			(net "GND")
		)
	)
	(footprint ""
		(layer "B.Cu")
		(at 53.415946 -321.554856 -90)
		(property "Reference" "C52"
			(at 0 0 90)
			(layer "B.SilkS")
			(hide yes)
			(effects
				(font
					(size 1.27 1.27)
				)
				(justify mirror)
			)
		)
		(property "Value" ""
			(at 0 0 90)
			(layer "B.Fab")
			(effects
				(font
					(size 1.27 1.27)
				)
				(justify mirror)
			)
		)
		(duplicate_pad_numbers_are_jumpers no)
		(fp_line
			(start -1.524 0.762)
			(end 1.524 0.762)
			(stroke
				(width 0.1524)
				(type default)
			)
			(layer "B.SilkS")
		)
		(fp_line
			(start 1.524 0.762)
			(end 1.524 -0.762)
			(stroke
				(width 0.1524)
				(type default)
			)
			(layer "B.SilkS")
		)
		(fp_line
			(start -1.524 -0.762)
			(end -1.524 0.762)
			(stroke
				(width 0.1524)
				(type default)
			)
			(layer "B.SilkS")
		)
		(fp_line
			(start 1.524 -0.762)
			(end -1.524 -0.762)
			(stroke
				(width 0.1524)
				(type default)
			)
			(layer "B.SilkS")
		)
		(fp_line
			(start -1.1049 0.724916)
			(end -1.1049 -0.724916)
			(stroke
				(width 0.1)
				(type default)
			)
			(layer "B.Fab")
		)
		(fp_line
			(start 1.1049 0.724916)
			(end -1.1049 0.724916)
			(stroke
				(width 0.1)
				(type default)
			)
			(layer "B.Fab")
		)
		(fp_line
			(start -1.1049 -0.724916)
			(end 1.1049 -0.724916)
			(stroke
				(width 0.1)
				(type default)
			)
			(layer "B.Fab")
		)
		(fp_line
			(start 1.1049 -0.724916)
			(end 1.1049 0.724916)
			(stroke
				(width 0.1)
				(type default)
			)
			(layer "B.Fab")
		)
		(pad "1" smd rect
			(at 0.889 0 270)
			(size 1.016 1.27)
			(layers "B.Cu" "B.Mask" "B.Paste")
			(net "P12V_S3_AUX_CPU1_NVDIMM")
		)
		(pad "2" smd rect
			(at -0.889 0 270)
			(size 1.016 1.27)
			(layers "B.Cu" "B.Mask" "B.Paste")
			(net "GND")
		)
	)
	(footprint ""
		(layer "B.Cu")
		(at 258.384802 -106.819192 180)
		(property "Reference" "R1196"
			(at 0 0 0)
			(layer "B.SilkS")
			(hide yes)
			(effects
				(font
					(size 1.27 1.27)
				)
				(justify mirror)
			)
		)
		(property "Value" ""
			(at 0 0 0)
			(layer "B.Fab")
			(effects
				(font
					(size 1.27 1.27)
				)
				(justify mirror)
			)
		)
		(duplicate_pad_numbers_are_jumpers no)
		(fp_line
			(start 0.7874 0.4064)
			(end 0.7874 -0.4064)
			(stroke
				(width 0.1524)
				(type default)
			)
			(layer "B.SilkS")
		)
		(fp_line
			(start 0.7874 -0.4064)
			(end -0.7874 -0.4064)
			(stroke
				(width 0.1524)
				(type default)
			)
			(layer "B.SilkS")
		)
		(fp_line
			(start -0.7874 0.4064)
			(end 0.7874 0.4064)
			(stroke
				(width 0.1524)
				(type default)
			)
			(layer "B.SilkS")
		)
		(fp_line
			(start -0.7874 -0.4064)
			(end -0.7874 0.4064)
			(stroke
				(width 0.1524)
				(type default)
			)
			(layer "B.SilkS")
		)
		(fp_line
			(start 0.67945 0.3048)
			(end 0.67945 -0.305054)
			(stroke
				(width 0.1)
				(type default)
			)
			(layer "B.Fab")
		)
		(fp_line
			(start 0.67945 -0.305054)
			(end 0.12065 -0.305054)
			(stroke
				(width 0.1)
				(type default)
			)
			(layer "B.Fab")
		)
		(fp_line
			(start 0.12065 0.3048)
			(end 0.67945 0.3048)
			(stroke
				(width 0.1)
				(type default)
			)
			(layer "B.Fab")
		)
		(fp_line
			(start 0.12065 0.2794)
			(end 0.12065 0.3048)
			(stroke
				(width 0.1)
				(type default)
			)
			(layer "B.Fab")
		)
		(fp_line
			(start 0.12065 -0.2794)
			(end -0.12065 -0.2794)
			(stroke
				(width 0.1)
				(type default)
			)
			(layer "B.Fab")
		)
		(fp_line
			(start 0.12065 -0.305054)
			(end 0.12065 -0.2794)
			(stroke
				(width 0.1)
				(type default)
			)
			(layer "B.Fab")
		)
		(fp_line
			(start -0.120396 0.3048)
			(end -0.120396 0.2794)
			(stroke
				(width 0.1)
				(type default)
			)
			(layer "B.Fab")
		)
		(fp_line
			(start -0.120396 0.2794)
			(end 0.12065 0.2794)
			(stroke
				(width 0.1)
				(type default)
			)
			(layer "B.Fab")
		)
		(fp_line
			(start -0.12065 -0.2794)
			(end -0.12065 -0.3048)
			(stroke
				(width 0.1)
				(type default)
			)
			(layer "B.Fab")
		)
		(fp_line
			(start -0.12065 -0.3048)
			(end -0.67945 -0.3048)
			(stroke
				(width 0.1)
				(type default)
			)
			(layer "B.Fab")
		)
		(fp_line
			(start -0.67945 0.3048)
			(end -0.120396 0.3048)
			(stroke
				(width 0.1)
				(type default)
			)
			(layer "B.Fab")
		)
		(fp_line
			(start -0.67945 -0.3048)
			(end -0.67945 0.3048)
			(stroke
				(width 0.1)
				(type default)
			)
			(layer "B.Fab")
		)
		(pad "1" smd circle
			(at 0.40005 0)
			(size 0 0)
			(layers "B.Cu" "B.Mask" "B.Paste")
			(net "FM_CK440_MXCK_25M_100M")
		)
		(pad "2" smd circle
			(at -0.40005 0)
			(size 0 0)
			(layers "B.Cu" "B.Mask" "B.Paste")
			(net "GND")
		)
	)
)
